# S9S_MB_2U (Grand Teton) — schematic netlist excerpt (pin names and nets, part order shuffled) for the footprints in the layout excerpt that follows; sources: Cadence DE-HDL packaged netlist, KiCad conversion of 03242023_DA0F0TMBIJ0_F0T_Motherboard_J_brd_V01_OCP.brd

R2587  Q_RES  4.7K 1% CHIP  pkg 0402LF  page 301 : A = HSC_VDD ; B = IRQ_HSC_FAULT_N
R96  Q_RES  240 1% EMPTY  pkg 0402LF  page 126 : A = PVNN_TERM_CPU0 ; B = PU_CPU0_UPI2_AC_COUPLING

(kicad_pcb
	(version 20260206)
	(generator "pcbnew")
	(generator_version "10.0")
	(general
		(thickness 1.6)
		(legacy_teardrops no)
	)
	(paper "A4")
	(title_block
		(title "03242023_DA0F0TMBIJ0_F0T_Motherboard_J_brd_V01_OCP.brd")
		(comment 1 "Grand Teton / footprints 6100-6101 of 6105")
	)
	(layers
		(0 "F.Cu" signal "TOP")
		(4 "In1.Cu" signal "GND")
		(6 "In2.Cu" signal "IN1")
		(8 "In3.Cu" signal "GND1")
		(10 "In4.Cu" signal "IN2")
		(12 "In5.Cu" signal "GND2")
		(14 "In6.Cu" signal "IN3")
		(16 "In7.Cu" signal "GND3")
		(18 "In8.Cu" signal "VCC")
		(20 "In9.Cu" signal "VCC1")
		(22 "In10.Cu" signal "GND4")
		(24 "In11.Cu" signal "IN4")
		(26 "In12.Cu" signal "GND5")
		(28 "In13.Cu" signal "IN5")
		(30 "In14.Cu" signal "GND6")
		(32 "In15.Cu" signal "IN6")
		(34 "In16.Cu" signal "GND7")
		(2 "B.Cu" signal "BOTTOM")
		(9 "F.Adhes" user "F.Adhesive")
		(11 "B.Adhes" user "B.Adhesive")
		(13 "F.Paste" user "Package Geometry/Pastemask Top")
		(15 "B.Paste" user "Package Geometry/Pastemask Bottom")
		(5 "F.SilkS" user "Ref Des/Silkscreen Top")
		(7 "B.SilkS" user "Ref Des/Silkscreen Bottom")
		(1 "F.Mask" user "Board Geometry/Soldermask Top")
		(3 "B.Mask" user "Board Geometry/Soldermask Bottom")
		(17 "Dwgs.User" user "User.Drawings")
		(19 "Cmts.User" user "User.Comments")
		(21 "Eco1.User" user "User.Eco1")
		(23 "Eco2.User" user "User.Eco2")
		(25 "Edge.Cuts" user "Board Geometry/Outline")
		(27 "Margin" user)
		(31 "F.CrtYd" user "Package Geometry/Place Bound Top")
		(29 "B.CrtYd" user "Package Geometry/Place Bound Bottom")
		(35 "F.Fab" user "Ref Des/Assembly Top")
		(33 "B.Fab" user "Ref Des/Assembly Bottom")
	)
	(footprint ""
		(layer "B.Cu")
		(at 192.052448 -401.772882 180)
		(property "Reference" "R2587"
			(at 0 0 0)
			(layer "B.SilkS")
			(hide yes)
			(effects
				(font
					(size 1.27 1.27)
				)
				(justify mirror)
			)
		)
		(property "Value" ""
			(at 0 0 0)
			(layer "B.Fab")
			(effects
				(font
					(size 1.27 1.27)
				)
				(justify mirror)
			)
		)
		(duplicate_pad_numbers_are_jumpers no)
		(fp_line
			(start 0.7874 0.4064)
			(end 0.7874 -0.4064)
			(stroke
				(width 0.1524)
				(type default)
			)
			(layer "B.SilkS")
		)
		(fp_line
			(start 0.7874 -0.4064)
			(end -0.7874 -0.4064)
			(stroke
				(width 0.1524)
				(type default)
			)
			(layer "B.SilkS")
		)
		(fp_line
			(start -0.7874 0.4064)
			(end 0.7874 0.4064)
			(stroke
				(width 0.1524)
				(type default)
			)
			(layer "B.SilkS")
		)
		(fp_line
			(start -0.7874 -0.4064)
			(end -0.7874 0.4064)
			(stroke
				(width 0.1524)
				(type default)
			)
			(layer "B.SilkS")
		)
		(fp_line
			(start 0.67945 0.3048)
			(end 0.67945 -0.305054)
			(stroke
				(width 0.1)
				(type default)
			)
			(layer "B.Fab")
		)
		(fp_line
			(start 0.67945 -0.305054)
			(end 0.12065 -0.305054)
			(stroke
				(width 0.1)
				(type default)
			)
			(layer "B.Fab")
		)
		(fp_line
			(start 0.12065 0.3048)
			(end 0.67945 0.3048)
			(stroke
				(width 0.1)
				(type default)
			)
			(layer "B.Fab")
		)
		(fp_line
			(start 0.12065 0.2794)
			(end 0.12065 0.3048)
			(stroke
				(width 0.1)
				(type default)
			)
			(layer "B.Fab")
		)
		(fp_line
			(start 0.12065 -0.2794)
			(end -0.12065 -0.2794)
			(stroke
				(width 0.1)
				(type default)
			)
			(layer "B.Fab")
		)
		(fp_line
			(start 0.12065 -0.305054)
			(end 0.12065 -0.2794)
			(stroke
				(width 0.1)
				(type default)
			)
			(layer "B.Fab")
		)
		(fp_line
			(start -0.120396 0.3048)
			(end -0.120396 0.2794)
			(stroke
				(width 0.1)
				(type default)
			)
			(layer "B.Fab")
		)
		(fp_line
			(start -0.120396 0.2794)
			(end 0.12065 0.2794)
			(stroke
				(width 0.1)
				(type default)
			)
			(layer "B.Fab")
		)
		(fp_line
			(start -0.12065 -0.2794)
			(end -0.12065 -0.3048)
			(stroke
				(width 0.1)
				(type default)
			)
			(layer "B.Fab")
		)
		(fp_line
			(start -0.12065 -0.3048)
			(end -0.67945 -0.3048)
			(stroke
				(width 0.1)
				(type default)
			)
			(layer "B.Fab")
		)
		(fp_line
			(start -0.67945 0.3048)
			(end -0.120396 0.3048)
			(stroke
				(width 0.1)
				(type default)
			)
			(layer "B.Fab")
		)
		(fp_line
			(start -0.67945 -0.3048)
			(end -0.67945 0.3048)
			(stroke
				(width 0.1)
				(type default)
			)
			(layer "B.Fab")
		)
		(pad "1" smd circle
			(at 0.40005 0)
			(size 0 0)
			(layers "B.Cu" "B.Mask" "B.Paste")
			(net "HSC_VDD")
		)
		(pad "2" smd circle
			(at -0.40005 0)
			(size 0 0)
			(layers "B.Cu" "B.Mask" "B.Paste")
			(net "IRQ_HSC_FAULT_N")
		)
	)
	(footprint ""
		(layer "B.Cu")
		(at 282.11272 -193.710814 -90)
		(property "Reference" "R96"
			(at 0 0 90)
			(layer "B.SilkS")
			(hide yes)
			(effects
				(font
					(size 1.27 1.27)
				)
				(justify mirror)
			)
		)
		(property "Value" ""
			(at 0 0 90)
			(layer "B.Fab")
			(effects
				(font
					(size 1.27 1.27)
				)
				(justify mirror)
			)
		)
		(duplicate_pad_numbers_are_jumpers no)
		(fp_line
			(start -0.7874 0.4064)
			(end 0.7874 0.4064)
			(stroke
				(width 0.1524)
				(type default)
			)
			(layer "B.SilkS")
		)
		(fp_line
			(start 0.7874 0.4064)
			(end 0.7874 -0.4064)
			(stroke
				(width 0.1524)
				(type default)
			)
			(layer "B.SilkS")
		)
		(fp_line
			(start -0.7874 -0.4064)
			(end -0.7874 0.4064)
			(stroke
				(width 0.1524)
				(type default)
			)
			(layer "B.SilkS")
		)
		(fp_line
			(start 0.7874 -0.4064)
			(end -0.7874 -0.4064)
			(stroke
				(width 0.1524)
				(type default)
			)
			(layer "B.SilkS")
		)
		(fp_line
			(start -0.67945 0.3048)
			(end -0.120396 0.3048)
			(stroke
				(width 0.1)
				(type default)
			)
			(layer "B.Fab")
		)
		(fp_line
			(start -0.120396 0.3048)
			(end -0.120396 0.2794)
			(stroke
				(width 0.1)
				(type default)
			)
			(layer "B.Fab")
		)
		(fp_line
			(start 0.12065 0.3048)
			(end 0.67945 0.3048)
			(stroke
				(width 0.1)
				(type default)
			)
			(layer "B.Fab")
		)
		(fp_line
			(start 0.67945 0.3048)
			(end 0.67945 -0.305054)
			(stroke
				(width 0.1)
				(type default)
			)
			(layer "B.Fab")
		)
		(fp_line
			(start -0.120396 0.2794)
			(end 0.12065 0.2794)
			(stroke
				(width 0.1)
				(type default)
			)
			(layer "B.Fab")
		)
		(fp_line
			(start 0.12065 0.2794)
			(end 0.12065 0.3048)
			(stroke
				(width 0.1)
				(type default)
			)
			(layer "B.Fab")
		)
		(fp_line
			(start -0.12065 -0.2794)
			(end -0.12065 -0.3048)
			(stroke
				(width 0.1)
				(type default)
			)
			(layer "B.Fab")
		)
		(fp_line
			(start 0.12065 -0.2794)
			(end -0.12065 -0.2794)
			(stroke
				(width 0.1)
				(type default)
			)
			(layer "B.Fab")
		)
		(fp_line
			(start -0.67945 -0.3048)
			(end -0.67945 0.3048)
			(stroke
				(width 0.1)
				(type default)
			)
			(layer "B.Fab")
		)
		(fp_line
			(start -0.12065 -0.3048)
			(end -0.67945 -0.3048)
			(stroke
				(width 0.1)
				(type default)
			)
			(layer "B.Fab")
		)
		(fp_line
			(start 0.12065 -0.305054)
			(end 0.12065 -0.2794)
			(stroke
				(width 0.1)
				(type default)
			)
			(layer "B.Fab")
		)
		(fp_line
			(start 0.67945 -0.305054)
			(end 0.12065 -0.305054)
			(stroke
				(width 0.1)
				(type default)
			)
			(layer "B.Fab")
		)
		(pad "1" smd circle
			(at 0.40005 0 90)
			(size 0 0)
			(layers "B.Cu" "B.Mask" "B.Paste")
			(net "PVNN_TERM_CPU0")
		)
		(pad "2" smd circle
			(at -0.40005 0 90)
			(size 0 0)
			(layers "B.Cu" "B.Mask" "B.Paste")
			(net "PU_CPU0_UPI2_AC_COUPLING")
		)
	)
)
